(kicad_pcb
	(version 20260206)
	(generator "pcbnew")
	(generator_version "10.0")
	(general
		(thickness 1.6)
		(legacy_teardrops no)
	)
	(paper "A4")
	(title_block
		(title "04192023_DAF0TMB3IC0_F0TG_MB_C_brd_V02_OCP.brd")
		(comment 1 "Grand Teton / footprint 230 of 8354 (J100), pads 227-291 of 291")
	)
	(layers
		(0 "F.Cu" signal "TOP")
		(4 "In1.Cu" signal "GND")
		(6 "In2.Cu" signal "IN1")
		(8 "In3.Cu" signal "GND1")
		(10 "In4.Cu" signal "IN2")
		(12 "In5.Cu" signal "GND2")
		(14 "In6.Cu" signal "IN3")
		(16 "In7.Cu" signal "GND3")
		(18 "In8.Cu" signal "VCC")
		(20 "In9.Cu" signal "VCC1")
		(22 "In10.Cu" signal "GND4")
		(24 "In11.Cu" signal "IN4")
		(26 "In12.Cu" signal "GND5")
		(28 "In13.Cu" signal "IN5")
		(30 "In14.Cu" signal "GND6")
		(32 "In15.Cu" signal "IN6")
		(34 "In16.Cu" signal "GND7")
		(2 "B.Cu" signal "BOTTOM")
		(9 "F.Adhes" user "F.Adhesive")
		(11 "B.Adhes" user "B.Adhesive")
		(13 "F.Paste" user "Package Geometry/Pastemask Top")
		(15 "B.Paste" user "Package Geometry/Pastemask Bottom")
		(5 "F.SilkS" user "Ref Des/Silkscreen Top")
		(7 "B.SilkS" user "Ref Des/Silkscreen Bottom")
		(1 "F.Mask" user "Board Geometry/Soldermask Top")
		(3 "B.Mask" user "Board Geometry/Soldermask Bottom")
		(17 "Dwgs.User" user "User.Drawings")
		(19 "Cmts.User" user "User.Comments")
		(21 "Eco1.User" user "User.Eco1")
		(23 "Eco2.User" user "User.Eco2")
		(25 "Edge.Cuts" user "Board Geometry/Outline")
		(27 "Margin" user)
		(31 "F.CrtYd" user "Package Geometry/Place Bound Top")
		(29 "B.CrtYd" user "Package Geometry/Place Bound Bottom")
		(35 "F.Fab" user "Ref Des/Assembly Top")
		(33 "B.Fab" user "Ref Des/Assembly Bottom")
	)
	(footprint ""
		(layer "F.Cu")
		(at 181.566058 -255.560322 180)
		(property "Reference" "J100"
			(at -2.7178 -81.857088 0)
			(unlocked yes)
			(layer "F.SilkS")
			(effects
				(font
					(size 0.7874 0.5842)
					(thickness 0.1524)
				)
			)
		)
		(property "Value" ""
			(at 0 0 180)
			(layer "F.Fab")
			(effects
				(font
					(size 1.27 1.27)
				)
			)
		)
		(duplicate_pad_numbers_are_jumpers no)
		(pad "227" smd rect
			(at 2.050034 11.474958 90)
			(size 0.519938 1.4986)
			(layers "F.Cu" "F.Mask" "F.Paste")
			(net "M_I_CPU1_SB_PAR")
		)
		(pad "228" smd rect
			(at 2.050034 12.325096 90)
			(size 0.519938 1.4986)
			(layers "F.Cu" "F.Mask" "F.Paste")
			(net "GND")
		)
		(pad "229" smd rect
			(at 2.050034 13.17498 90)
			(size 0.519938 1.4986)
			(layers "F.Cu" "F.Mask" "F.Paste")
			(net "M_I_CPU1_SB_CS_N<1>")
		)
		(pad "230" smd rect
			(at 2.050034 14.025118 90)
			(size 0.519938 1.4986)
			(layers "F.Cu" "F.Mask" "F.Paste")
			(net "GND")
		)
		(pad "231" smd rect
			(at 2.050034 14.875002 90)
			(size 0.519938 1.4986)
			(layers "F.Cu" "F.Mask" "F.Paste")
			(net "Net_2373")
		)
		(pad "232" smd rect
			(at 2.050034 15.724886 90)
			(size 0.519938 1.4986)
			(layers "F.Cu" "F.Mask" "F.Paste")
			(net "Net_2374")
		)
		(pad "233" smd rect
			(at 2.050034 16.575024 90)
			(size 0.519938 1.4986)
			(layers "F.Cu" "F.Mask" "F.Paste")
			(net "GND")
		)
		(pad "234" smd rect
			(at 2.050034 17.424908 90)
			(size 0.519938 1.4986)
			(layers "F.Cu" "F.Mask" "F.Paste")
			(net "M_I_CPU1_SB_CB<6>")
		)
		(pad "235" smd rect
			(at 2.050034 18.275046 90)
			(size 0.519938 1.4986)
			(layers "F.Cu" "F.Mask" "F.Paste")
			(net "GND")
		)
		(pad "236" smd rect
			(at 2.050034 19.12493 90)
			(size 0.519938 1.4986)
			(layers "F.Cu" "F.Mask" "F.Paste")
			(net "M_I_CPU1_SB_CB<7>")
		)
		(pad "237" smd rect
			(at 2.050034 19.975068 90)
			(size 0.519938 1.4986)
			(layers "F.Cu" "F.Mask" "F.Paste")
			(net "GND")
		)
		(pad "238" smd rect
			(at 2.050034 20.824952 90)
			(size 0.519938 1.4986)
			(layers "F.Cu" "F.Mask" "F.Paste")
			(net "M_I_CPU1_SB_DQS_DN<4>")
		)
		(pad "239" smd rect
			(at 2.050034 21.67509 90)
			(size 0.519938 1.4986)
			(layers "F.Cu" "F.Mask" "F.Paste")
			(net "M_I_CPU1_SB_DQS_DP<4>")
		)
		(pad "240" smd rect
			(at 2.050034 22.524974 90)
			(size 0.519938 1.4986)
			(layers "F.Cu" "F.Mask" "F.Paste")
			(net "GND")
		)
		(pad "241" smd rect
			(at 2.050034 23.375112 90)
			(size 0.519938 1.4986)
			(layers "F.Cu" "F.Mask" "F.Paste")
			(net "M_I_CPU1_SB_CB<2>")
		)
		(pad "242" smd rect
			(at 2.050034 24.224996 90)
			(size 0.519938 1.4986)
			(layers "F.Cu" "F.Mask" "F.Paste")
			(net "GND")
		)
		(pad "243" smd rect
			(at 2.050034 25.07488 90)
			(size 0.519938 1.4986)
			(layers "F.Cu" "F.Mask" "F.Paste")
			(net "M_I_CPU1_SB_CB<3>")
		)
		(pad "244" smd rect
			(at 2.050034 25.925018 90)
			(size 0.519938 1.4986)
			(layers "F.Cu" "F.Mask" "F.Paste")
			(net "GND")
		)
		(pad "245" smd rect
			(at 2.050034 26.774902 90)
			(size 0.519938 1.4986)
			(layers "F.Cu" "F.Mask" "F.Paste")
			(net "M_I_CPU1_SB_DQ<2>")
		)
		(pad "246" smd rect
			(at 2.050034 27.62504 90)
			(size 0.519938 1.4986)
			(layers "F.Cu" "F.Mask" "F.Paste")
			(net "GND")
		)
		(pad "247" smd rect
			(at 2.050034 28.474924 90)
			(size 0.519938 1.4986)
			(layers "F.Cu" "F.Mask" "F.Paste")
			(net "M_I_CPU1_SB_DQ<3>")
		)
		(pad "248" smd rect
			(at 2.050034 29.325062 90)
			(size 0.519938 1.4986)
			(layers "F.Cu" "F.Mask" "F.Paste")
			(net "GND")
		)
		(pad "249" smd rect
			(at 2.050034 30.174946 90)
			(size 0.519938 1.4986)
			(layers "F.Cu" "F.Mask" "F.Paste")
			(net "M_I_CPU1_SB_DQS_DN<5>")
		)
		(pad "250" smd rect
			(at 2.050034 31.025084 90)
			(size 0.519938 1.4986)
			(layers "F.Cu" "F.Mask" "F.Paste")
			(net "M_I_CPU1_SB_DQS_DP<5>")
		)
		(pad "251" smd rect
			(at 2.050034 31.874968 90)
			(size 0.519938 1.4986)
			(layers "F.Cu" "F.Mask" "F.Paste")
			(net "GND")
		)
		(pad "252" smd rect
			(at 2.050034 32.725106 90)
			(size 0.519938 1.4986)
			(layers "F.Cu" "F.Mask" "F.Paste")
			(net "M_I_CPU1_SB_DQ<6>")
		)
		(pad "253" smd rect
			(at 2.050034 33.57499 90)
			(size 0.519938 1.4986)
			(layers "F.Cu" "F.Mask" "F.Paste")
			(net "GND")
		)
		(pad "254" smd rect
			(at 2.050034 34.425128 90)
			(size 0.519938 1.4986)
			(layers "F.Cu" "F.Mask" "F.Paste")
			(net "M_I_CPU1_SB_DQ<7>")
		)
		(pad "255" smd rect
			(at 2.050034 35.275012 90)
			(size 0.519938 1.4986)
			(layers "F.Cu" "F.Mask" "F.Paste")
			(net "GND")
		)
		(pad "256" smd rect
			(at 2.050034 36.124896 90)
			(size 0.519938 1.4986)
			(layers "F.Cu" "F.Mask" "F.Paste")
			(net "M_I_CPU1_SB_DQ<10>")
		)
		(pad "257" smd rect
			(at 2.050034 36.975034 90)
			(size 0.519938 1.4986)
			(layers "F.Cu" "F.Mask" "F.Paste")
			(net "GND")
		)
		(pad "258" smd rect
			(at 2.050034 37.824918 90)
			(size 0.519938 1.4986)
			(layers "F.Cu" "F.Mask" "F.Paste")
			(net "M_I_CPU1_SB_DQ<11>")
		)
		(pad "259" smd rect
			(at 2.050034 38.675056 90)
			(size 0.519938 1.4986)
			(layers "F.Cu" "F.Mask" "F.Paste")
			(net "GND")
		)
		(pad "260" smd rect
			(at 2.050034 39.52494 90)
			(size 0.519938 1.4986)
			(layers "F.Cu" "F.Mask" "F.Paste")
			(net "M_I_CPU1_SB_DQS_DN<6>")
		)
		(pad "261" smd rect
			(at 2.050034 40.375078 90)
			(size 0.519938 1.4986)
			(layers "F.Cu" "F.Mask" "F.Paste")
			(net "M_I_CPU1_SB_DQS_DP<6>")
		)
		(pad "262" smd rect
			(at 2.050034 41.224962 90)
			(size 0.519938 1.4986)
			(layers "F.Cu" "F.Mask" "F.Paste")
			(net "GND")
		)
		(pad "263" smd rect
			(at 2.050034 42.0751 90)
			(size 0.519938 1.4986)
			(layers "F.Cu" "F.Mask" "F.Paste")
			(net "M_I_CPU1_SB_DQ<14>")
		)
		(pad "264" smd rect
			(at 2.050034 42.924984 90)
			(size 0.519938 1.4986)
			(layers "F.Cu" "F.Mask" "F.Paste")
			(net "GND")
		)
		(pad "265" smd rect
			(at 2.050034 43.775122 90)
			(size 0.519938 1.4986)
			(layers "F.Cu" "F.Mask" "F.Paste")
			(net "M_I_CPU1_SB_DQ<15>")
		)
		(pad "266" smd rect
			(at 2.050034 44.625006 90)
			(size 0.519938 1.4986)
			(layers "F.Cu" "F.Mask" "F.Paste")
			(net "GND")
		)
		(pad "267" smd rect
			(at 2.050034 45.47489 90)
			(size 0.519938 1.4986)
			(layers "F.Cu" "F.Mask" "F.Paste")
			(net "M_I_CPU1_SB_DQ<18>")
		)
		(pad "268" smd rect
			(at 2.050034 46.325028 90)
			(size 0.519938 1.4986)
			(layers "F.Cu" "F.Mask" "F.Paste")
			(net "GND")
		)
		(pad "269" smd rect
			(at 2.050034 47.174912 90)
			(size 0.519938 1.4986)
			(layers "F.Cu" "F.Mask" "F.Paste")
			(net "M_I_CPU1_SB_DQ<19>")
		)
		(pad "270" smd rect
			(at 2.050034 48.02505 90)
			(size 0.519938 1.4986)
			(layers "F.Cu" "F.Mask" "F.Paste")
			(net "GND")
		)
		(pad "271" smd rect
			(at 2.050034 48.874934 90)
			(size 0.519938 1.4986)
			(layers "F.Cu" "F.Mask" "F.Paste")
			(net "M_I_CPU1_SB_DQS_DN<7>")
		)
		(pad "272" smd rect
			(at 2.050034 49.725072 90)
			(size 0.519938 1.4986)
			(layers "F.Cu" "F.Mask" "F.Paste")
			(net "M_I_CPU1_SB_DQS_DP<7>")
		)
		(pad "273" smd rect
			(at 2.050034 50.574956 90)
			(size 0.519938 1.4986)
			(layers "F.Cu" "F.Mask" "F.Paste")
			(net "GND")
		)
		(pad "274" smd rect
			(at 2.050034 51.425094 90)
			(size 0.519938 1.4986)
			(layers "F.Cu" "F.Mask" "F.Paste")
			(net "M_I_CPU1_SB_DQ<22>")
		)
		(pad "275" smd rect
			(at 2.050034 52.274978 90)
			(size 0.519938 1.4986)
			(layers "F.Cu" "F.Mask" "F.Paste")
			(net "GND")
		)
		(pad "276" smd rect
			(at 2.050034 53.125116 90)
			(size 0.519938 1.4986)
			(layers "F.Cu" "F.Mask" "F.Paste")
			(net "M_I_CPU1_SB_DQ<23>")
		)
		(pad "277" smd rect
			(at 2.050034 53.975 90)
			(size 0.519938 1.4986)
			(layers "F.Cu" "F.Mask" "F.Paste")
			(net "GND")
		)
		(pad "278" smd rect
			(at 2.050034 54.824884 90)
			(size 0.519938 1.4986)
			(layers "F.Cu" "F.Mask" "F.Paste")
			(net "M_I_CPU1_SB_DQ<26>")
		)
		(pad "279" smd rect
			(at 2.050034 55.675022 90)
			(size 0.519938 1.4986)
			(layers "F.Cu" "F.Mask" "F.Paste")
			(net "GND")
		)
		(pad "280" smd rect
			(at 2.050034 56.524906 90)
			(size 0.519938 1.4986)
			(layers "F.Cu" "F.Mask" "F.Paste")
			(net "M_I_CPU1_SB_DQ<27>")
		)
		(pad "281" smd rect
			(at 2.050034 57.375044 90)
			(size 0.519938 1.4986)
			(layers "F.Cu" "F.Mask" "F.Paste")
			(net "GND")
		)
		(pad "282" smd rect
			(at 2.050034 58.224928 90)
			(size 0.519938 1.4986)
			(layers "F.Cu" "F.Mask" "F.Paste")
			(net "M_I_CPU1_SB_DQS_DN<8>")
		)
		(pad "283" smd rect
			(at 2.050034 59.075066 90)
			(size 0.519938 1.4986)
			(layers "F.Cu" "F.Mask" "F.Paste")
			(net "M_I_CPU1_SB_DQS_DP<8>")
		)
		(pad "284" smd rect
			(at 2.050034 59.92495 90)
			(size 0.519938 1.4986)
			(layers "F.Cu" "F.Mask" "F.Paste")
			(net "GND")
		)
		(pad "285" smd rect
			(at 2.050034 60.775088 90)
			(size 0.519938 1.4986)
			(layers "F.Cu" "F.Mask" "F.Paste")
			(net "M_I_CPU1_SB_DQ<30>")
		)
		(pad "286" smd rect
			(at 2.050034 61.624972 90)
			(size 0.519938 1.4986)
			(layers "F.Cu" "F.Mask" "F.Paste")
			(net "GND")
		)
		(pad "287" smd rect
			(at 2.050034 62.47511 90)
			(size 0.519938 1.4986)
			(layers "F.Cu" "F.Mask" "F.Paste")
			(net "M_I_CPU1_SB_DQ<31>")
		)
		(pad "288" smd rect
			(at 2.050034 63.324994 90)
			(size 0.519938 1.4986)
			(layers "F.Cu" "F.Mask" "F.Paste")
			(net "GND")
		)
		(pad "G1" thru_hole oval
			(at 0 -68.97497 90)
			(size 1.7272 3.4798)
			(drill oval 1.2192 2.4638)
			(layers "*.Cu" "*.Mask")
			(remove_unused_layers no)
			(net "GND")
			(clearance 0.127)
			(thermal_gap 0.127)
		)
		(pad "G2" thru_hole oval
			(at 0 3.875024 90)
			(size 1.7272 3.4798)
			(drill oval 1.2192 2.4638)
			(layers "*.Cu" "*.Mask")
			(remove_unused_layers no)
			(net "GND")
			(clearance 0.127)
			(thermal_gap 0.127)
		)
		(pad "G3" thru_hole oval
			(at 0 68.97497 90)
			(size 1.7272 3.4798)
			(drill oval 1.2192 2.4638)
			(layers "*.Cu" "*.Mask")
			(remove_unused_layers no)
			(net "GND")
			(clearance 0.127)
			(thermal_gap 0.127)
		)
	)
)
